(kicad_pcb
	(version 20260206)
	(generator "pcbnew")
	(generator_version "10.0")
	(general
		(thickness 1.6)
		(legacy_teardrops no)
	)
	(paper "A4")
	(title_block
		(title "03242023_DA0F0TMBIJ0_F0T_Motherboard_J_brd_V01_OCP.brd")
		(comment 1 "Grand Teton / footprints 1479-1484 of 6105")
	)
	(layers
		(0 "F.Cu" signal "TOP")
		(4 "In1.Cu" signal "GND")
		(6 "In2.Cu" signal "IN1")
		(8 "In3.Cu" signal "GND1")
		(10 "In4.Cu" signal "IN2")
		(12 "In5.Cu" signal "GND2")
		(14 "In6.Cu" signal "IN3")
		(16 "In7.Cu" signal "GND3")
		(18 "In8.Cu" signal "VCC")
		(20 "In9.Cu" signal "VCC1")
		(22 "In10.Cu" signal "GND4")
		(24 "In11.Cu" signal "IN4")
		(26 "In12.Cu" signal "GND5")
		(28 "In13.Cu" signal "IN5")
		(30 "In14.Cu" signal "GND6")
		(32 "In15.Cu" signal "IN6")
		(34 "In16.Cu" signal "GND7")
		(2 "B.Cu" signal "BOTTOM")
		(9 "F.Adhes" user "F.Adhesive")
		(11 "B.Adhes" user "B.Adhesive")
		(13 "F.Paste" user "Package Geometry/Pastemask Top")
		(15 "B.Paste" user "Package Geometry/Pastemask Bottom")
		(5 "F.SilkS" user "Ref Des/Silkscreen Top")
		(7 "B.SilkS" user "Ref Des/Silkscreen Bottom")
		(1 "F.Mask" user "Board Geometry/Soldermask Top")
		(3 "B.Mask" user "Board Geometry/Soldermask Bottom")
		(17 "Dwgs.User" user "User.Drawings")
		(19 "Cmts.User" user "User.Comments")
		(21 "Eco1.User" user "User.Eco1")
		(23 "Eco2.User" user "User.Eco2")
		(25 "Edge.Cuts" user "Board Geometry/Outline")
		(27 "Margin" user)
		(31 "F.CrtYd" user "Package Geometry/Place Bound Top")
		(29 "B.CrtYd" user "Package Geometry/Place Bound Bottom")
		(35 "F.Fab" user "Ref Des/Assembly Top")
		(33 "B.Fab" user "Ref Des/Assembly Bottom")
	)
	(footprint ""
		(layer "F.Cu")
		(at 216.065608 -404.823422)
		(property "Reference" "PC2183"
			(at 0 0 0)
			(layer "F.SilkS")
			(hide yes)
			(effects
				(font
					(size 1.27 1.27)
				)
			)
		)
		(property "Value" ""
			(at 0 0 0)
			(layer "F.Fab")
			(effects
				(font
					(size 1.27 1.27)
				)
			)
		)
		(duplicate_pad_numbers_are_jumpers no)
		(fp_line
			(start -0.7874 -0.4064)
			(end 0.7874 -0.4064)
			(stroke
				(width 0.1524)
				(type default)
			)
			(layer "F.SilkS")
		)
		(fp_line
			(start -0.7874 0.4064)
			(end -0.7874 -0.4064)
			(stroke
				(width 0.1524)
				(type default)
			)
			(layer "F.SilkS")
		)
		(fp_line
			(start 0.7874 -0.4064)
			(end 0.7874 0.4064)
			(stroke
				(width 0.1524)
				(type default)
			)
			(layer "F.SilkS")
		)
		(fp_line
			(start 0.7874 0.4064)
			(end -0.7874 0.4064)
			(stroke
				(width 0.1524)
				(type default)
			)
			(layer "F.SilkS")
		)
		(fp_line
			(start -0.67945 -0.305054)
			(end -0.12065 -0.305054)
			(stroke
				(width 0.1)
				(type default)
			)
			(layer "F.Fab")
		)
		(fp_line
			(start -0.67945 0.3048)
			(end -0.67945 -0.305054)
			(stroke
				(width 0.1)
				(type default)
			)
			(layer "F.Fab")
		)
		(fp_line
			(start -0.12065 -0.305054)
			(end -0.12065 -0.2794)
			(stroke
				(width 0.1)
				(type default)
			)
			(layer "F.Fab")
		)
		(fp_line
			(start -0.12065 -0.2794)
			(end 0.12065 -0.2794)
			(stroke
				(width 0.1)
				(type default)
			)
			(layer "F.Fab")
		)
		(fp_line
			(start -0.12065 0.2794)
			(end -0.12065 0.3048)
			(stroke
				(width 0.1)
				(type default)
			)
			(layer "F.Fab")
		)
		(fp_line
			(start -0.12065 0.3048)
			(end -0.67945 0.3048)
			(stroke
				(width 0.1)
				(type default)
			)
			(layer "F.Fab")
		)
		(fp_line
			(start 0.120396 0.2794)
			(end -0.12065 0.2794)
			(stroke
				(width 0.1)
				(type default)
			)
			(layer "F.Fab")
		)
		(fp_line
			(start 0.120396 0.3048)
			(end 0.120396 0.2794)
			(stroke
				(width 0.1)
				(type default)
			)
			(layer "F.Fab")
		)
		(fp_line
			(start 0.12065 -0.3048)
			(end 0.67945 -0.3048)
			(stroke
				(width 0.1)
				(type default)
			)
			(layer "F.Fab")
		)
		(fp_line
			(start 0.12065 -0.2794)
			(end 0.12065 -0.3048)
			(stroke
				(width 0.1)
				(type default)
			)
			(layer "F.Fab")
		)
		(fp_line
			(start 0.67945 -0.3048)
			(end 0.67945 0.3048)
			(stroke
				(width 0.1)
				(type default)
			)
			(layer "F.Fab")
		)
		(fp_line
			(start 0.67945 0.3048)
			(end 0.120396 0.3048)
			(stroke
				(width 0.1)
				(type default)
			)
			(layer "F.Fab")
		)
		(pad "1" smd circle
			(at -0.40005 0)
			(size 0 0)
			(layers "F.Cu" "F.Mask" "F.Paste")
			(net "HSC_ON")
		)
		(pad "2" smd circle
			(at 0.40005 0)
			(size 0 0)
			(layers "F.Cu" "F.Mask" "F.Paste")
			(net "AGND_HSC")
		)
	)
	(footprint ""
		(layer "F.Cu")
		(at 17.190974 -92.687648 90)
		(property "Reference" "R3662"
			(at 0 0 90)
			(layer "F.SilkS")
			(hide yes)
			(effects
				(font
					(size 1.27 1.27)
				)
			)
		)
		(property "Value" ""
			(at 0 0 90)
			(layer "F.Fab")
			(effects
				(font
					(size 1.27 1.27)
				)
			)
		)
		(duplicate_pad_numbers_are_jumpers no)
		(fp_line
			(start 0.7874 -0.4064)
			(end 0.7874 0.4064)
			(stroke
				(width 0.1524)
				(type default)
			)
			(layer "F.SilkS")
		)
		(fp_line
			(start -0.7874 -0.4064)
			(end 0.7874 -0.4064)
			(stroke
				(width 0.1524)
				(type default)
			)
			(layer "F.SilkS")
		)
		(fp_line
			(start 0.7874 0.4064)
			(end -0.7874 0.4064)
			(stroke
				(width 0.1524)
				(type default)
			)
			(layer "F.SilkS")
		)
		(fp_line
			(start -0.7874 0.4064)
			(end -0.7874 -0.4064)
			(stroke
				(width 0.1524)
				(type default)
			)
			(layer "F.SilkS")
		)
		(fp_line
			(start -0.12065 -0.305054)
			(end -0.12065 -0.2794)
			(stroke
				(width 0.1)
				(type default)
			)
			(layer "F.Fab")
		)
		(fp_line
			(start -0.67945 -0.305054)
			(end -0.12065 -0.305054)
			(stroke
				(width 0.1)
				(type default)
			)
			(layer "F.Fab")
		)
		(fp_line
			(start 0.67945 -0.3048)
			(end 0.67945 0.3048)
			(stroke
				(width 0.1)
				(type default)
			)
			(layer "F.Fab")
		)
		(fp_line
			(start 0.12065 -0.3048)
			(end 0.67945 -0.3048)
			(stroke
				(width 0.1)
				(type default)
			)
			(layer "F.Fab")
		)
		(fp_line
			(start 0.12065 -0.2794)
			(end 0.12065 -0.3048)
			(stroke
				(width 0.1)
				(type default)
			)
			(layer "F.Fab")
		)
		(fp_line
			(start -0.12065 -0.2794)
			(end 0.12065 -0.2794)
			(stroke
				(width 0.1)
				(type default)
			)
			(layer "F.Fab")
		)
		(fp_line
			(start 0.120396 0.2794)
			(end -0.12065 0.2794)
			(stroke
				(width 0.1)
				(type default)
			)
			(layer "F.Fab")
		)
		(fp_line
			(start -0.12065 0.2794)
			(end -0.12065 0.3048)
			(stroke
				(width 0.1)
				(type default)
			)
			(layer "F.Fab")
		)
		(fp_line
			(start 0.67945 0.3048)
			(end 0.120396 0.3048)
			(stroke
				(width 0.1)
				(type default)
			)
			(layer "F.Fab")
		)
		(fp_line
			(start 0.120396 0.3048)
			(end 0.120396 0.2794)
			(stroke
				(width 0.1)
				(type default)
			)
			(layer "F.Fab")
		)
		(fp_line
			(start -0.12065 0.3048)
			(end -0.67945 0.3048)
			(stroke
				(width 0.1)
				(type default)
			)
			(layer "F.Fab")
		)
		(fp_line
			(start -0.67945 0.3048)
			(end -0.67945 -0.305054)
			(stroke
				(width 0.1)
				(type default)
			)
			(layer "F.Fab")
		)
		(pad "1" smd circle
			(at -0.40005 0 90)
			(size 0 0)
			(layers "F.Cu" "F.Mask" "F.Paste")
			(net "P3V3_AUX_USB_HUB")
		)
		(pad "2" smd circle
			(at 0.40005 0 90)
			(size 0 0)
			(layers "F.Cu" "F.Mask" "F.Paste")
			(net "USB_HUB_DVDD")
		)
	)
	(footprint ""
		(layer "F.Cu")
		(at 128.02616 -96.495108 90)
		(property "Reference" "R4403"
			(at 0 0 90)
			(layer "F.SilkS")
			(hide yes)
			(effects
				(font
					(size 1.27 1.27)
				)
			)
		)
		(property "Value" ""
			(at 0 0 90)
			(layer "F.Fab")
			(effects
				(font
					(size 1.27 1.27)
				)
			)
		)
		(duplicate_pad_numbers_are_jumpers no)
		(fp_line
			(start 0.7874 -0.4064)
			(end 0.7874 0.4064)
			(stroke
				(width 0.1524)
				(type default)
			)
			(layer "F.SilkS")
		)
		(fp_line
			(start -0.7874 -0.4064)
			(end 0.7874 -0.4064)
			(stroke
				(width 0.1524)
				(type default)
			)
			(layer "F.SilkS")
		)
		(fp_line
			(start 0.7874 0.4064)
			(end -0.7874 0.4064)
			(stroke
				(width 0.1524)
				(type default)
			)
			(layer "F.SilkS")
		)
		(fp_line
			(start -0.7874 0.4064)
			(end -0.7874 -0.4064)
			(stroke
				(width 0.1524)
				(type default)
			)
			(layer "F.SilkS")
		)
		(fp_line
			(start -0.12065 -0.305054)
			(end -0.12065 -0.2794)
			(stroke
				(width 0.1)
				(type default)
			)
			(layer "F.Fab")
		)
		(fp_line
			(start -0.67945 -0.305054)
			(end -0.12065 -0.305054)
			(stroke
				(width 0.1)
				(type default)
			)
			(layer "F.Fab")
		)
		(fp_line
			(start 0.67945 -0.3048)
			(end 0.67945 0.3048)
			(stroke
				(width 0.1)
				(type default)
			)
			(layer "F.Fab")
		)
		(fp_line
			(start 0.12065 -0.3048)
			(end 0.67945 -0.3048)
			(stroke
				(width 0.1)
				(type default)
			)
			(layer "F.Fab")
		)
		(fp_line
			(start 0.12065 -0.2794)
			(end 0.12065 -0.3048)
			(stroke
				(width 0.1)
				(type default)
			)
			(layer "F.Fab")
		)
		(fp_line
			(start -0.12065 -0.2794)
			(end 0.12065 -0.2794)
			(stroke
				(width 0.1)
				(type default)
			)
			(layer "F.Fab")
		)
		(fp_line
			(start 0.120396 0.2794)
			(end -0.12065 0.2794)
			(stroke
				(width 0.1)
				(type default)
			)
			(layer "F.Fab")
		)
		(fp_line
			(start -0.12065 0.2794)
			(end -0.12065 0.3048)
			(stroke
				(width 0.1)
				(type default)
			)
			(layer "F.Fab")
		)
		(fp_line
			(start 0.67945 0.3048)
			(end 0.120396 0.3048)
			(stroke
				(width 0.1)
				(type default)
			)
			(layer "F.Fab")
		)
		(fp_line
			(start 0.120396 0.3048)
			(end 0.120396 0.2794)
			(stroke
				(width 0.1)
				(type default)
			)
			(layer "F.Fab")
		)
		(fp_line
			(start -0.12065 0.3048)
			(end -0.67945 0.3048)
			(stroke
				(width 0.1)
				(type default)
			)
			(layer "F.Fab")
		)
		(fp_line
			(start -0.67945 0.3048)
			(end -0.67945 -0.305054)
			(stroke
				(width 0.1)
				(type default)
			)
			(layer "F.Fab")
		)
		(pad "1" smd circle
			(at -0.40005 0 90)
			(size 0 0)
			(layers "F.Cu" "F.Mask" "F.Paste")
			(net "H_CPU0_MEMHOT_OUT")
		)
		(pad "2" smd circle
			(at 0.40005 0 90)
			(size 0 0)
			(layers "F.Cu" "F.Mask" "F.Paste")
			(net "H_CPU0_MEMHOT_OUT_R")
		)
	)
	(footprint ""
		(layer "F.Cu")
		(at 234.11688 -256.123948 -90)
		(property "Reference" "R4075"
			(at 0 0 270)
			(layer "F.SilkS")
			(hide yes)
			(effects
				(font
					(size 1.27 1.27)
				)
			)
		)
		(property "Value" ""
			(at 0 0 270)
			(layer "F.Fab")
			(effects
				(font
					(size 1.27 1.27)
				)
			)
		)
		(duplicate_pad_numbers_are_jumpers no)
		(fp_line
			(start -0.7874 0.4064)
			(end -0.7874 -0.4064)
			(stroke
				(width 0.1524)
				(type default)
			)
			(layer "F.SilkS")
		)
		(fp_line
			(start 0.7874 0.4064)
			(end -0.7874 0.4064)
			(stroke
				(width 0.1524)
				(type default)
			)
			(layer "F.SilkS")
		)
		(fp_line
			(start -0.7874 -0.4064)
			(end 0.7874 -0.4064)
			(stroke
				(width 0.1524)
				(type default)
			)
			(layer "F.SilkS")
		)
		(fp_line
			(start 0.7874 -0.4064)
			(end 0.7874 0.4064)
			(stroke
				(width 0.1524)
				(type default)
			)
			(layer "F.SilkS")
		)
		(fp_line
			(start -0.67945 0.3048)
			(end -0.67945 -0.305054)
			(stroke
				(width 0.1)
				(type default)
			)
			(layer "F.Fab")
		)
		(fp_line
			(start -0.12065 0.3048)
			(end -0.67945 0.3048)
			(stroke
				(width 0.1)
				(type default)
			)
			(layer "F.Fab")
		)
		(fp_line
			(start 0.120396 0.3048)
			(end 0.120396 0.2794)
			(stroke
				(width 0.1)
				(type default)
			)
			(layer "F.Fab")
		)
		(fp_line
			(start 0.67945 0.3048)
			(end 0.120396 0.3048)
			(stroke
				(width 0.1)
				(type default)
			)
			(layer "F.Fab")
		)
		(fp_line
			(start -0.12065 0.2794)
			(end -0.12065 0.3048)
			(stroke
				(width 0.1)
				(type default)
			)
			(layer "F.Fab")
		)
		(fp_line
			(start 0.120396 0.2794)
			(end -0.12065 0.2794)
			(stroke
				(width 0.1)
				(type default)
			)
			(layer "F.Fab")
		)
		(fp_line
			(start -0.12065 -0.2794)
			(end 0.12065 -0.2794)
			(stroke
				(width 0.1)
				(type default)
			)
			(layer "F.Fab")
		)
		(fp_line
			(start 0.12065 -0.2794)
			(end 0.12065 -0.3048)
			(stroke
				(width 0.1)
				(type default)
			)
			(layer "F.Fab")
		)
		(fp_line
			(start 0.12065 -0.3048)
			(end 0.67945 -0.3048)
			(stroke
				(width 0.1)
				(type default)
			)
			(layer "F.Fab")
		)
		(fp_line
			(start 0.67945 -0.3048)
			(end 0.67945 0.3048)
			(stroke
				(width 0.1)
				(type default)
			)
			(layer "F.Fab")
		)
		(fp_line
			(start -0.67945 -0.305054)
			(end -0.12065 -0.305054)
			(stroke
				(width 0.1)
				(type default)
			)
			(layer "F.Fab")
		)
		(fp_line
			(start -0.12065 -0.305054)
			(end -0.12065 -0.2794)
			(stroke
				(width 0.1)
				(type default)
			)
			(layer "F.Fab")
		)
		(pad "1" smd circle
			(at -0.40005 0 270)
			(size 0 0)
			(layers "F.Cu" "F.Mask" "F.Paste")
			(net "CLK_GEN2_BMC_RC_OE_N")
		)
		(pad "2" smd circle
			(at 0.40005 0 270)
			(size 0 0)
			(layers "F.Cu" "F.Mask" "F.Paste")
			(net "CLK_GEN2_BMC_RC_OE_R3_N")
		)
	)
	(footprint ""
		(layer "F.Cu")
		(at 263.65962 -130.602228 180)
		(property "Reference" "R4540"
			(at 0 0 180)
			(layer "F.SilkS")
			(hide yes)
			(effects
				(font
					(size 1.27 1.27)
				)
			)
		)
		(property "Value" ""
			(at 0 0 180)
			(layer "F.Fab")
			(effects
				(font
					(size 1.27 1.27)
				)
			)
		)
		(duplicate_pad_numbers_are_jumpers no)
		(fp_line
			(start 0.7874 0.4064)
			(end -0.7874 0.4064)
			(stroke
				(width 0.1524)
				(type default)
			)
			(layer "F.SilkS")
		)
		(fp_line
			(start 0.7874 -0.4064)
			(end 0.7874 0.4064)
			(stroke
				(width 0.1524)
				(type default)
			)
			(layer "F.SilkS")
		)
		(fp_line
			(start -0.7874 0.4064)
			(end -0.7874 -0.4064)
			(stroke
				(width 0.1524)
				(type default)
			)
			(layer "F.SilkS")
		)
		(fp_line
			(start -0.7874 -0.4064)
			(end 0.7874 -0.4064)
			(stroke
				(width 0.1524)
				(type default)
			)
			(layer "F.SilkS")
		)
		(fp_line
			(start 0.67945 0.3048)
			(end 0.120396 0.3048)
			(stroke
				(width 0.1)
				(type default)
			)
			(layer "F.Fab")
		)
		(fp_line
			(start 0.67945 -0.3048)
			(end 0.67945 0.3048)
			(stroke
				(width 0.1)
				(type default)
			)
			(layer "F.Fab")
		)
		(fp_line
			(start 0.12065 -0.2794)
			(end 0.12065 -0.3048)
			(stroke
				(width 0.1)
				(type default)
			)
			(layer "F.Fab")
		)
		(fp_line
			(start 0.12065 -0.3048)
			(end 0.67945 -0.3048)
			(stroke
				(width 0.1)
				(type default)
			)
			(layer "F.Fab")
		)
		(fp_line
			(start 0.120396 0.3048)
			(end 0.120396 0.2794)
			(stroke
				(width 0.1)
				(type default)
			)
			(layer "F.Fab")
		)
		(fp_line
			(start 0.120396 0.2794)
			(end -0.12065 0.2794)
			(stroke
				(width 0.1)
				(type default)
			)
			(layer "F.Fab")
		)
		(fp_line
			(start -0.12065 0.3048)
			(end -0.67945 0.3048)
			(stroke
				(width 0.1)
				(type default)
			)
			(layer "F.Fab")
		)
		(fp_line
			(start -0.12065 0.2794)
			(end -0.12065 0.3048)
			(stroke
				(width 0.1)
				(type default)
			)
			(layer "F.Fab")
		)
		(fp_line
			(start -0.12065 -0.2794)
			(end 0.12065 -0.2794)
			(stroke
				(width 0.1)
				(type default)
			)
			(layer "F.Fab")
		)
		(fp_line
			(start -0.12065 -0.305054)
			(end -0.12065 -0.2794)
			(stroke
				(width 0.1)
				(type default)
			)
			(layer "F.Fab")
		)
		(fp_line
			(start -0.67945 0.3048)
			(end -0.67945 -0.305054)
			(stroke
				(width 0.1)
				(type default)
			)
			(layer "F.Fab")
		)
		(fp_line
			(start -0.67945 -0.305054)
			(end -0.12065 -0.305054)
			(stroke
				(width 0.1)
				(type default)
			)
			(layer "F.Fab")
		)
		(pad "1" smd circle
			(at -0.40005 0 180)
			(size 0 0)
			(layers "F.Cu" "F.Mask" "F.Paste")
			(net "SMB_HOST_CLK_BUF_ISO_3V3AUX_S_1")
		)
		(pad "2" smd circle
			(at 0.40005 0 180)
			(size 0 0)
			(layers "F.Cu" "F.Mask" "F.Paste")
			(net "SMB_HOST_CLK_BUF_ISO_3V3AUX_SCL")
		)
	)
	(footprint ""
		(layer "F.Cu")
		(at 150.622 -133.314948)
		(property "Reference" "R4605"
			(at 0 0 0)
			(layer "F.SilkS")
			(hide yes)
			(effects
				(font
					(size 1.27 1.27)
				)
			)
		)
		(property "Value" ""
			(at 0 0 0)
			(layer "F.Fab")
			(effects
				(font
					(size 1.27 1.27)
				)
			)
		)
		(duplicate_pad_numbers_are_jumpers no)
		(fp_line
			(start -0.7874 -0.4064)
			(end 0.7874 -0.4064)
			(stroke
				(width 0.1524)
				(type default)
			)
			(layer "F.SilkS")
		)
		(fp_line
			(start -0.7874 0.4064)
			(end -0.7874 -0.4064)
			(stroke
				(width 0.1524)
				(type default)
			)
			(layer "F.SilkS")
		)
		(fp_line
			(start 0.7874 -0.4064)
			(end 0.7874 0.4064)
			(stroke
				(width 0.1524)
				(type default)
			)
			(layer "F.SilkS")
		)
		(fp_line
			(start 0.7874 0.4064)
			(end -0.7874 0.4064)
			(stroke
				(width 0.1524)
				(type default)
			)
			(layer "F.SilkS")
		)
		(fp_line
			(start -0.67945 -0.305054)
			(end -0.12065 -0.305054)
			(stroke
				(width 0.1)
				(type default)
			)
			(layer "F.Fab")
		)
		(fp_line
			(start -0.67945 0.3048)
			(end -0.67945 -0.305054)
			(stroke
				(width 0.1)
				(type default)
			)
			(layer "F.Fab")
		)
		(fp_line
			(start -0.12065 -0.305054)
			(end -0.12065 -0.2794)
			(stroke
				(width 0.1)
				(type default)
			)
			(layer "F.Fab")
		)
		(fp_line
			(start -0.12065 -0.2794)
			(end 0.12065 -0.2794)
			(stroke
				(width 0.1)
				(type default)
			)
			(layer "F.Fab")
		)
		(fp_line
			(start -0.12065 0.2794)
			(end -0.12065 0.3048)
			(stroke
				(width 0.1)
				(type default)
			)
			(layer "F.Fab")
		)
		(fp_line
			(start -0.12065 0.3048)
			(end -0.67945 0.3048)
			(stroke
				(width 0.1)
				(type default)
			)
			(layer "F.Fab")
		)
		(fp_line
			(start 0.120396 0.2794)
			(end -0.12065 0.2794)
			(stroke
				(width 0.1)
				(type default)
			)
			(layer "F.Fab")
		)
		(fp_line
			(start 0.120396 0.3048)
			(end 0.120396 0.2794)
			(stroke
				(width 0.1)
				(type default)
			)
			(layer "F.Fab")
		)
		(fp_line
			(start 0.12065 -0.3048)
			(end 0.67945 -0.3048)
			(stroke
				(width 0.1)
				(type default)
			)
			(layer "F.Fab")
		)
		(fp_line
			(start 0.12065 -0.2794)
			(end 0.12065 -0.3048)
			(stroke
				(width 0.1)
				(type default)
			)
			(layer "F.Fab")
		)
		(fp_line
			(start 0.67945 -0.3048)
			(end 0.67945 0.3048)
			(stroke
				(width 0.1)
				(type default)
			)
			(layer "F.Fab")
		)
		(fp_line
			(start 0.67945 0.3048)
			(end 0.120396 0.3048)
			(stroke
				(width 0.1)
				(type default)
			)
			(layer "F.Fab")
		)
		(pad "1" smd circle
			(at -0.40005 0)
			(size 0 0)
			(layers "F.Cu" "F.Mask" "F.Paste")
			(net "P3V3_AUX")
		)
		(pad "2" smd circle
			(at 0.40005 0)
			(size 0 0)
			(layers "F.Cu" "F.Mask" "F.Paste")
			(net "PWRGD_PS_PWROK_PLD_ISO")
		)
	)
)
